(kicad_pcb
	(version 20221018)
	(generator pcbnew)
	(general
    (thickness 1.62)
  )
	(paper "A4")
	(title_block
    (title "ECP5 - Datacenter Secure Control Module (DC-SCM)")
    (date "2024-07-01")
    (rev "1.2.1")
		(comment 9 "footprints 420-425 of 506")
	)
	(layers
    (0 "F.Cu" signal)
    (1 "In1.Cu" power)
    (2 "In2.Cu" signal)
    (3 "In3.Cu" power)
    (4 "In4.Cu" power)
    (5 "In5.Cu" signal)
    (6 "In6.Cu" power)
    (31 "B.Cu" signal)
    (32 "B.Adhes" user "B.Adhesive")
    (33 "F.Adhes" user "F.Adhesive")
    (34 "B.Paste" user)
    (35 "F.Paste" user)
    (36 "B.SilkS" user "B.Silkscreen")
    (37 "F.SilkS" user "F.Silkscreen")
    (38 "B.Mask" user)
    (39 "F.Mask" user)
    (40 "Dwgs.User" user "User.Drawings")
    (41 "Cmts.User" user "User.Comments")
    (42 "Eco1.User" user "User.Eco1")
    (43 "Eco2.User" user "User.Eco2")
    (44 "Edge.Cuts" user)
    (45 "Margin" user)
    (46 "B.CrtYd" user "B.Courtyard")
    (47 "F.CrtYd" user "F.Courtyard")
    (48 "B.Fab" user)
    (49 "F.Fab" user)
  )
	(footprint "antmicro-footprints:R_0402_1005Metric" (layer "B.Cu")
    (at 79.975 138.8 -90)
    (descr "Resistor SMD 0402")
    (tags "resistor SMD 0402")
    (property "Author" "Antmicro")
    (property "License" "Apache-2.0")
    (property "MPN" "CR0402-FX-1002GLF")
    (property "Manufacturer" "Bourns")
    (property "Public" "False")
    (property "Sheetfile" "rot.kicad_sch")
    (property "Sheetname" "RoT")
    (property "Tolerance" "1%")
    (property "Val" "10k")
    (property "ki_description" "SMD Chip Resistor, 10 kohm, ± 1%, 62.5 mW, 0402 [1005 Metric], Thick Film, General Purpose")
    (property "ki_keywords" "0402, SMT, RESISTOR, PASSIVE")
    (attr smd)
    (fp_text reference "R38" (at 3.05 -0.302498 90) (layer "B.SilkS")
        (effects (font (size 0.7 0.7) (thickness 0.127)) (justify mirror))
    )
    (fp_text value "R_10k_0402" (at 0 -1.17 90) (layer "B.Fab")
        (effects (font (size 1 1) (thickness 0.15)) (justify mirror))
    )
    (fp_text user "${REFERENCE}" (at 0 0 90) (layer "B.Fab")
        (effects (font (size 0.25 0.25) (thickness 0.04)) (justify mirror))
    )
    (fp_text user "Author: Antmicro" (at -0.95 -4.169 90) (layer "B.Fab") hide
        (effects (font (size 0.7 0.7) (thickness 0.15)) (justify left bottom mirror))
    )
    (fp_text user "License: Apache-2.0" (at -0.95 -5.169 90) (layer "B.Fab") hide
        (effects (font (size 0.7 0.7) (thickness 0.15)) (justify left bottom mirror))
    )
    (fp_rect (start -0.925 0.47) (end 0.925 -0.47)
      (stroke (width 0.05) (type default)) (fill none) (layer "B.CrtYd"))
    (fp_rect (start -0.5 0.25) (end 0.5 -0.25)
      (stroke (width 0.15) (type solid)) (fill none) (layer "B.Fab"))
    (pad "1" smd roundrect (at -0.48 0 270) (size 0.59 0.64) (layers "B.Cu" "B.Paste" "B.Mask") (roundrect_rratio 0.25)
      (net 128 "QSPIB1_D3") (pintype "passive"))
    (pad "2" smd roundrect (at 0.48 0 270) (size 0.59 0.64) (layers "B.Cu" "B.Paste" "B.Mask") (roundrect_rratio 0.25)
      (net 2 "VCC3V3") (pintype "passive"))
  )
	(footprint "antmicro-footprints:R_0402_1005Metric" (layer "B.Cu")
    (at 77.975 138.8 -90)
    (descr "Resistor SMD 0402")
    (tags "resistor SMD 0402")
    (property "Author" "Antmicro")
    (property "License" "Apache-2.0")
    (property "MPN" "CR0402-FX-1002GLF")
    (property "Manufacturer" "Bourns")
    (property "Public" "False")
    (property "Sheetfile" "rot.kicad_sch")
    (property "Sheetname" "RoT")
    (property "Tolerance" "1%")
    (property "Val" "10k")
    (property "ki_description" "SMD Chip Resistor, 10 kohm, ± 1%, 62.5 mW, 0402 [1005 Metric], Thick Film, General Purpose")
    (property "ki_keywords" "0402, SMT, RESISTOR, PASSIVE")
    (attr smd)
    (fp_text reference "R42" (at 3.05 -0.254166 90) (layer "B.SilkS")
        (effects (font (size 0.7 0.7) (thickness 0.127)) (justify mirror))
    )
    (fp_text value "R_10k_0402" (at 0 -1.17 90) (layer "B.Fab")
        (effects (font (size 1 1) (thickness 0.15)) (justify mirror))
    )
    (fp_text user "Author: Antmicro" (at -0.95 -4.169 90) (layer "B.Fab") hide
        (effects (font (size 0.7 0.7) (thickness 0.15)) (justify left bottom mirror))
    )
    (fp_text user "License: Apache-2.0" (at -0.95 -5.169 90) (layer "B.Fab") hide
        (effects (font (size 0.7 0.7) (thickness 0.15)) (justify left bottom mirror))
    )
    (fp_text user "${REFERENCE}" (at 0 0 90) (layer "B.Fab")
        (effects (font (size 0.25 0.25) (thickness 0.04)) (justify mirror))
    )
    (fp_rect (start -0.925 0.47) (end 0.925 -0.47)
      (stroke (width 0.05) (type default)) (fill none) (layer "B.CrtYd"))
    (fp_rect (start -0.5 0.25) (end 0.5 -0.25)
      (stroke (width 0.15) (type solid)) (fill none) (layer "B.Fab"))
    (pad "1" smd roundrect (at -0.48 0 270) (size 0.59 0.64) (layers "B.Cu" "B.Paste" "B.Mask") (roundrect_rratio 0.25)
      (net 126 "QSPIB1_D1") (pintype "passive"))
    (pad "2" smd roundrect (at 0.48 0 270) (size 0.59 0.64) (layers "B.Cu" "B.Paste" "B.Mask") (roundrect_rratio 0.25)
      (net 2 "VCC3V3") (pintype "passive"))
  )
	(footprint "antmicro-footprints:C_0402_1005Metric" (layer "B.Cu")
    (at 85.85 132.7 90)
    (descr "Capacitor SMD 0402")
    (tags "capacitor SMD 0402")
    (property "Author" "Antmicro")
    (property "Dielectric" "X5R")
    (property "License" "Apache-2.0")
    (property "MPN" "GRM155R61H104KE14D")
    (property "Manufacturer" "Murata")
    (property "Public" "False")
    (property "Sheetfile" "fpga-banks.kicad_sch")
    (property "Sheetname" "FPGA banks")
    (property "Val" "100n")
    (property "Voltage" "50V")
    (property "ki_description" "SMD Multilayer Ceramic Capacitor, 0.1 µF, 50 V, 0402 [1005 Metric], ± 10%, X5R, GRM Series")
    (property "ki_keywords" "0402, SMT, CAPACITOR, PASSIVE, CERAMIC, MLCC")
    (attr smd)
    (fp_text reference "C208" (at 0 1.17 90) (layer "B.SilkS")
        (effects (font (size 0.7 0.7) (thickness 0.127)) (justify mirror))
    )
    (fp_text value "C_100n_0402" (at 0 -1.17 90) (layer "B.Fab")
        (effects (font (size 1 1) (thickness 0.15)) (justify mirror))
    )
    (fp_text user "Author: Antmicro" (at -0.939 -3.399 270) (layer "B.Fab") hide
        (effects (font (size 0.7 0.7) (thickness 0.15)) (justify left bottom mirror))
    )
    (fp_text user "${REFERENCE}" (at 0 0 90) (layer "B.Fab")
        (effects (font (size 0.25 0.25) (thickness 0.04)) (justify mirror))
    )
    (fp_text user "License: Apache-2.0" (at -0.939 -5.799 270) (layer "B.Fab") hide
        (effects (font (size 0.7 0.7) (thickness 0.15)) (justify left bottom mirror))
    )
    (fp_rect (start -0.925 0.47) (end 0.925 -0.47)
      (stroke (width 0.05) (type default)) (fill none) (layer "B.CrtYd"))
    (fp_line (start -0.494 -0.248) (end -0.494 0.25)
      (stroke (width 0.15) (type solid)) (layer "B.Fab"))
    (fp_line (start -0.494 0.25) (end 0.504 0.25)
      (stroke (width 0.15) (type solid)) (layer "B.Fab"))
    (fp_line (start 0.504 -0.248) (end -0.494 -0.248)
      (stroke (width 0.15) (type solid)) (layer "B.Fab"))
    (fp_line (start 0.504 0.25) (end 0.504 -0.248)
      (stroke (width 0.15) (type solid)) (layer "B.Fab"))
    (pad "1" smd roundrect (at -0.48 0 90) (size 0.59 0.64) (layers "B.Cu" "B.Paste" "B.Mask") (roundrect_rratio 0.25)
      (net 1 "GND") (pintype "passive"))
    (pad "2" smd roundrect (at 0.48 0 90) (size 0.59 0.64) (layers "B.Cu" "B.Paste" "B.Mask") (roundrect_rratio 0.25)
      (net 268 "PROGRAM_N") (pintype "passive"))
  )
	(footprint "antmicro-footprints:R_0402_1005Metric" (layer "B.Cu")
    (at 84.75 132.7 -90)
    (descr "Resistor SMD 0402")
    (tags "resistor SMD 0402")
    (property "Author" "Antmicro")
    (property "License" "Apache-2.0")
    (property "MPN" "CR0402-FX-1002GLF")
    (property "Manufacturer" "Bourns")
    (property "Public" "False")
    (property "Sheetfile" "fpga-banks.kicad_sch")
    (property "Sheetname" "FPGA banks")
    (property "Tolerance" "1%")
    (property "Val" "10k")
    (property "ki_description" "SMD Chip Resistor, 10 kohm, ± 1%, 62.5 mW, 0402 [1005 Metric], Thick Film, General Purpose")
    (property "ki_keywords" "0402, SMT, RESISTOR, PASSIVE")
    (attr smd)
    (fp_text reference "R131" (at 0.655 1.01 90) (layer "B.SilkS")
        (effects (font (size 0.7 0.7) (thickness 0.127)) (justify mirror))
    )
    (fp_text value "R_10k_0402" (at 0 -1.17 90) (layer "B.Fab")
        (effects (font (size 1 1) (thickness 0.15)) (justify mirror))
    )
    (fp_text user "Author: Antmicro" (at -0.95 -4.169 90) (layer "B.Fab") hide
        (effects (font (size 0.7 0.7) (thickness 0.15)) (justify left bottom mirror))
    )
    (fp_text user "License: Apache-2.0" (at -0.95 -5.169 90) (layer "B.Fab") hide
        (effects (font (size 0.7 0.7) (thickness 0.15)) (justify left bottom mirror))
    )
    (fp_text user "${REFERENCE}" (at 0 0 90) (layer "B.Fab")
        (effects (font (size 0.25 0.25) (thickness 0.04)) (justify mirror))
    )
    (fp_rect (start -0.925 0.47) (end 0.925 -0.47)
      (stroke (width 0.05) (type default)) (fill none) (layer "B.CrtYd"))
    (fp_rect (start -0.5 0.25) (end 0.5 -0.25)
      (stroke (width 0.15) (type solid)) (fill none) (layer "B.Fab"))
    (pad "1" smd roundrect (at -0.48 0 270) (size 0.59 0.64) (layers "B.Cu" "B.Paste" "B.Mask") (roundrect_rratio 0.25)
      (net 268 "PROGRAM_N") (pintype "passive"))
    (pad "2" smd roundrect (at 0.48 0 270) (size 0.59 0.64) (layers "B.Cu" "B.Paste" "B.Mask") (roundrect_rratio 0.25)
      (net 2 "VCC3V3") (pintype "passive"))
  )
	(footprint "antmicro-footprints:R_Array_8x0602_Panasonic_EXB2HV" (layer "B.Cu")
    (at 84.74 116.3 90)
    (descr "Chip Resistor Network, ROHM MNR18")
    (tags "resistor array")
    (property "Author" "Antmicro")
    (property "License" "Apache-2.0")
    (property "MPN" "EXB2HV510JV")
    (property "Manufacturer" "Panasonic")
    (property "Sheetfile" "ddr3.kicad_sch")
    (property "Sheetname" "DDR3")
    (property "Val" "8x51R_0602")
    (property "ki_description" "Fixed Network Resistor, 51 ohm, Isolated, 8 Resistors, 1506 [3816 Metric], Convex, ± 5%")
    (property "ki_keywords" "SMT, RESISTOR, PASSIVE, ARRAY")
    (attr smd)
    (fp_text reference "R124" (at 2.195 0.74) (layer "B.SilkS")
        (effects (font (size 0.7 0.7) (thickness 0.127)) (justify mirror))
    )
    (fp_text value "8x51R_0602_array" (at 0 -3 270) (layer "B.Fab")
        (effects (font (size 1 1) (thickness 0.15)) (justify mirror))
    )
    (fp_text user "Author: Antmicro" (at -1.55 -5.05 270) (layer "B.Fab") hide
        (effects (font (size 0.7 0.7) (thickness 0.15)) (justify left bottom mirror))
    )
    (fp_text user "License: Apache-2.0" (at -1.55 -7.45 270) (layer "B.Fab") hide
        (effects (font (size 0.7 0.7) (thickness 0.15)) (justify left bottom mirror))
    )
    (fp_text user "${REFERENCE}" (at 0 0) (layer "B.Fab")
        (effects (font (size 1 1) (thickness 0.15)) (justify mirror))
    )
    (fp_line (start 0.5 -2.12) (end -0.5 -2.12)
      (stroke (width 0.15) (type solid)) (layer "B.SilkS"))
    (fp_line (start 0.5 2.12) (end -0.5 2.12)
      (stroke (width 0.15) (type solid)) (layer "B.SilkS"))
    (fp_circle (center -1.05 2.05) (end -1 2.05)
      (stroke (width 0.15) (type solid)) (fill solid) (layer "B.SilkS"))
    (fp_rect (start -1.55 2.2) (end 1.55 -2.2)
      (stroke (width 0.05) (type solid)) (fill none) (layer "B.CrtYd"))
    (fp_line (start -0.8 -2) (end 0.8 -2)
      (stroke (width 0.15) (type solid)) (layer "B.Fab"))
    (fp_line (start -0.8 2) (end -0.8 -2)
      (stroke (width 0.15) (type solid)) (layer "B.Fab"))
    (fp_line (start 0.8 -2) (end 0.8 2)
      (stroke (width 0.15) (type solid)) (layer "B.Fab"))
    (fp_line (start 0.8 2) (end -0.8 2)
      (stroke (width 0.15) (type solid)) (layer "B.Fab"))
    (pad "1" smd rect (at -0.9 1.75 90) (size 0.8 0.3) (layers "B.Cu" "B.Paste" "B.Mask")
      (net 240 "DDR3_A7") (pinfunction "1") (pintype "passive"))
    (pad "2" smd rect (at -0.9 1.25 90) (size 0.8 0.3) (layers "B.Cu" "B.Paste" "B.Mask")
      (net 255 "DDR3_A3") (pinfunction "2") (pintype "passive"))
    (pad "3" smd rect (at -0.9 0.75 90) (size 0.8 0.3) (layers "B.Cu" "B.Paste" "B.Mask")
      (net 241 "DDR3_A2") (pinfunction "3") (pintype "passive"))
    (pad "4" smd rect (at -0.9 0.25 90) (size 0.8 0.3) (layers "B.Cu" "B.Paste" "B.Mask")
      (net 253 "DDR3_A5") (pinfunction "4") (pintype "passive"))
    (pad "5" smd rect (at -0.9 -0.25 90) (size 0.8 0.3) (layers "B.Cu" "B.Paste" "B.Mask")
      (net 239 "DDR3_A9") (pinfunction "5") (pintype "passive"))
    (pad "6" smd rect (at -0.9 -0.75 90) (size 0.8 0.3) (layers "B.Cu" "B.Paste" "B.Mask")
      (net 237 "DDR3_A13") (pinfunction "6") (pintype "passive"))
    (pad "7" smd rect (at -0.9 -1.25 90) (size 0.8 0.3) (layers "B.Cu" "B.Paste" "B.Mask")
      (net 238 "DDR3_A11") (pinfunction "7") (pintype "passive"))
    (pad "8" smd rect (at -0.9 -1.75 90) (size 0.8 0.3) (layers "B.Cu" "B.Paste" "B.Mask")
      (net 244 "DDR3_A14") (pinfunction "8") (pintype "passive"))
    (pad "9" smd rect (at 0.9 -1.75 90) (size 0.8 0.3) (layers "B.Cu" "B.Paste" "B.Mask")
      (net 166 "/DDR3/DDR3_VTT") (pinfunction "9") (pintype "passive"))
    (pad "10" smd rect (at 0.9 -1.25 90) (size 0.8 0.3) (layers "B.Cu" "B.Paste" "B.Mask")
      (net 166 "/DDR3/DDR3_VTT") (pinfunction "10") (pintype "passive"))
    (pad "11" smd rect (at 0.9 -0.75 90) (size 0.8 0.3) (layers "B.Cu" "B.Paste" "B.Mask")
      (net 166 "/DDR3/DDR3_VTT") (pinfunction "11") (pintype "passive"))
    (pad "12" smd rect (at 0.9 -0.25 90) (size 0.8 0.3) (layers "B.Cu" "B.Paste" "B.Mask")
      (net 166 "/DDR3/DDR3_VTT") (pinfunction "12") (pintype "passive"))
    (pad "13" smd rect (at 0.9 0.25 90) (size 0.8 0.3) (layers "B.Cu" "B.Paste" "B.Mask")
      (net 166 "/DDR3/DDR3_VTT") (pinfunction "13") (pintype "passive"))
    (pad "14" smd rect (at 0.9 0.75 90) (size 0.8 0.3) (layers "B.Cu" "B.Paste" "B.Mask")
      (net 166 "/DDR3/DDR3_VTT") (pinfunction "14") (pintype "passive"))
    (pad "15" smd rect (at 0.9 1.25 90) (size 0.8 0.3) (layers "B.Cu" "B.Paste" "B.Mask")
      (net 166 "/DDR3/DDR3_VTT") (pinfunction "15") (pintype "passive"))
    (pad "16" smd rect (at 0.9 1.75 90) (size 0.8 0.3) (layers "B.Cu" "B.Paste" "B.Mask")
      (net 166 "/DDR3/DDR3_VTT") (pinfunction "16") (pintype "passive"))
  )
	(footprint "antmicro-footprints:R_Array_8x0602_Panasonic_EXB2HV" (layer "B.Cu")
    (at 78.94 119.795 180)
    (descr "Chip Resistor Network, ROHM MNR18")
    (tags "resistor array")
    (property "Author" "Antmicro")
    (property "License" "Apache-2.0")
    (property "MPN" "EXB2HV510JV")
    (property "Manufacturer" "Panasonic")
    (property "Sheetfile" "ddr3.kicad_sch")
    (property "Sheetname" "DDR3")
    (property "Val" "8x51R_0602")
    (property "ki_description" "Fixed Network Resistor, 51 ohm, Isolated, 8 Resistors, 1506 [3816 Metric], Convex, ± 5%")
    (property "ki_keywords" "SMT, RESISTOR, PASSIVE, ARRAY")
    (attr smd)
    (fp_text reference "R125" (at 2.26 -0.68 90) (layer "B.SilkS")
        (effects (font (size 0.7 0.7) (thickness 0.127)) (justify mirror))
    )
    (fp_text value "8x51R_0602_array" (at 0 -3) (layer "B.Fab")
        (effects (font (size 1 1) (thickness 0.15)) (justify mirror))
    )
    (fp_text user "${REFERENCE}" (at 0 0 -90) (layer "B.Fab")
        (effects (font (size 1 1) (thickness 0.15)) (justify mirror))
    )
    (fp_text user "Author: Antmicro" (at -1.55 -5.05) (layer "B.Fab") hide
        (effects (font (size 0.7 0.7) (thickness 0.15)) (justify left bottom mirror))
    )
    (fp_text user "License: Apache-2.0" (at -1.55 -7.45) (layer "B.Fab") hide
        (effects (font (size 0.7 0.7) (thickness 0.15)) (justify left bottom mirror))
    )
    (fp_line (start 0.5 -2.12) (end -0.5 -2.12)
      (stroke (width 0.15) (type solid)) (layer "B.SilkS"))
    (fp_line (start 0.5 2.12) (end -0.5 2.12)
      (stroke (width 0.15) (type solid)) (layer "B.SilkS"))
    (fp_circle (center -1.05 2.05) (end -1 2.05)
      (stroke (width 0.15) (type solid)) (fill solid) (layer "B.SilkS"))
    (fp_rect (start -1.55 2.2) (end 1.55 -2.2)
      (stroke (width 0.05) (type solid)) (fill none) (layer "B.CrtYd"))
    (fp_line (start -0.8 -2) (end 0.8 -2)
      (stroke (width 0.15) (type solid)) (layer "B.Fab"))
    (fp_line (start -0.8 2) (end -0.8 -2)
      (stroke (width 0.15) (type solid)) (layer "B.Fab"))
    (fp_line (start 0.8 -2) (end 0.8 2)
      (stroke (width 0.15) (type solid)) (layer "B.Fab"))
    (fp_line (start 0.8 2) (end -0.8 2)
      (stroke (width 0.15) (type solid)) (layer "B.Fab"))
    (pad "1" smd rect (at -0.9 1.75 180) (size 0.8 0.3) (layers "B.Cu" "B.Paste" "B.Mask")
      (net 243 "DDR3_A8") (pinfunction "1") (pintype "passive"))
    (pad "2" smd rect (at -0.9 1.25 180) (size 0.8 0.3) (layers "B.Cu" "B.Paste" "B.Mask")
      (net 242 "DDR3_A6") (pinfunction "2") (pintype "passive"))
    (pad "3" smd rect (at -0.9 0.75 180) (size 0.8 0.3) (layers "B.Cu" "B.Paste" "B.Mask")
      (net 245 "DDR3_A4") (pinfunction "3") (pintype "passive"))
    (pad "4" smd rect (at -0.9 0.25 180) (size 0.8 0.3) (layers "B.Cu" "B.Paste" "B.Mask")
      (net 247 "DDR3_A1") (pinfunction "4") (pintype "passive"))
    (pad "5" smd rect (at -0.9 -0.25 180) (size 0.8 0.3) (layers "B.Cu" "B.Paste" "B.Mask")
      (net 248 "DDR3_A12") (pinfunction "5") (pintype "passive"))
    (pad "6" smd rect (at -0.9 -0.75 180) (size 0.8 0.3) (layers "B.Cu" "B.Paste" "B.Mask")
      (net 249 "DDR3_BA1") (pinfunction "6") (pintype "passive"))
    (pad "7" smd rect (at -0.9 -1.25 180) (size 0.8 0.3) (layers "B.Cu" "B.Paste" "B.Mask")
      (net 250 "DDR3_A10") (pinfunction "7") (pintype "passive"))
    (pad "8" smd rect (at -0.9 -1.75 180) (size 0.8 0.3) (layers "B.Cu" "B.Paste" "B.Mask")
      (net 260 "DDR3_CKE") (pinfunction "8") (pintype "passive"))
    (pad "9" smd rect (at 0.9 -1.75 180) (size 0.8 0.3) (layers "B.Cu" "B.Paste" "B.Mask")
      (net 166 "/DDR3/DDR3_VTT") (pinfunction "9") (pintype "passive"))
    (pad "10" smd rect (at 0.9 -1.25 180) (size 0.8 0.3) (layers "B.Cu" "B.Paste" "B.Mask")
      (net 166 "/DDR3/DDR3_VTT") (pinfunction "10") (pintype "passive"))
    (pad "11" smd rect (at 0.9 -0.75 180) (size 0.8 0.3) (layers "B.Cu" "B.Paste" "B.Mask")
      (net 166 "/DDR3/DDR3_VTT") (pinfunction "11") (pintype "passive"))
    (pad "12" smd rect (at 0.9 -0.25 180) (size 0.8 0.3) (layers "B.Cu" "B.Paste" "B.Mask")
      (net 166 "/DDR3/DDR3_VTT") (pinfunction "12") (pintype "passive"))
    (pad "13" smd rect (at 0.9 0.25 180) (size 0.8 0.3) (layers "B.Cu" "B.Paste" "B.Mask")
      (net 166 "/DDR3/DDR3_VTT") (pinfunction "13") (pintype "passive"))
    (pad "14" smd rect (at 0.9 0.75 180) (size 0.8 0.3) (layers "B.Cu" "B.Paste" "B.Mask")
      (net 166 "/DDR3/DDR3_VTT") (pinfunction "14") (pintype "passive"))
    (pad "15" smd rect (at 0.9 1.25 180) (size 0.8 0.3) (layers "B.Cu" "B.Paste" "B.Mask")
      (net 166 "/DDR3/DDR3_VTT") (pinfunction "15") (pintype "passive"))
    (pad "16" smd rect (at 0.9 1.75 180) (size 0.8 0.3) (layers "B.Cu" "B.Paste" "B.Mask")
      (net 166 "/DDR3/DDR3_VTT") (pinfunction "16") (pintype "passive"))
  )
)
